(kicad_pcb
	(version 20260206)
	(generator "pcbnew")
	(generator_version "10.0")
	(general
		(thickness 1.6)
		(legacy_teardrops no)
	)
	(paper "A4")
	(title_block
		(title "fcb — 12433-1M.1206WZS1330.brd")
		(comment 1 "Open Vault / Knox (Wiwynn) / footprints 249-256 of 495")
	)
	(layers
		(0 "F.Cu" signal "TOP")
		(4 "In1.Cu" signal "L2GND")
		(6 "In2.Cu" signal "L3VCC")
		(2 "B.Cu" signal "BOTTOM")
		(9 "F.Adhes" user "F.Adhesive")
		(11 "B.Adhes" user "B.Adhesive")
		(13 "F.Paste" user "Package Geometry/Pastemask Top")
		(15 "B.Paste" user "Package Geometry/Pastemask Bottom")
		(5 "F.SilkS" user "Ref Des/Silkscreen Top")
		(7 "B.SilkS" user "Ref Des/Silkscreen Bottom")
		(1 "F.Mask" user "Board Geometry/Soldermask Top")
		(3 "B.Mask" user "Board Geometry/Soldermask Bottom")
		(17 "Dwgs.User" user "User.Drawings")
		(19 "Cmts.User" user "User.Comments")
		(21 "Eco1.User" user "User.Eco1")
		(23 "Eco2.User" user "User.Eco2")
		(25 "Edge.Cuts" user "Board Geometry/Outline")
		(27 "Margin" user)
		(31 "F.CrtYd" user "Package Geometry/Place Bound Top")
		(29 "B.CrtYd" user "Package Geometry/Place Bound Bottom")
		(35 "F.Fab" user "Ref Des/Assembly Top")
		(33 "B.Fab" user "Ref Des/Assembly Bottom")
	)
	(footprint ""
		(layer "F.Cu")
		(at 12.7 -447.1162 90)
		(property "Reference" "C46"
			(at 0 0 90)
			(layer "F.SilkS")
			(hide yes)
			(effects
				(font
					(size 1.27 1.27)
				)
			)
		)
		(property "Value" "SCD1U16V2KX-3GP"
			(at 1.1811 -2.7051 90)
			(unlocked yes)
			(layer "F.Fab")
			(hide yes)
			(effects
				(font
					(size 1.016 1.016)
					(thickness 0.1524)
				)
			)
		)
		(property "Device Type" "C402H22"
			(at 1.1811 -4.2291 90)
			(unlocked yes)
			(layer "F.Fab")
			(hide yes)
			(effects
				(font
					(size 1.016 1.016)
					(thickness 0.1524)
				)
			)
		)
		(duplicate_pad_numbers_are_jumpers no)
		(fp_rect
			(start -0.4318 0.9525)
			(end 0.4318 -0.9525)
			(stroke
				(width 0)
				(type default)
			)
			(fill no)
			(layer "F.CrtYd")
		)
		(fp_rect
			(start -0.4318 0.9525)
			(end 0.4318 -0.9525)
			(stroke
				(width 0)
				(type default)
			)
			(fill no)
			(layer "F.Fab")
		)
		(pad "1" smd custom
			(at 0 -0.4445 90)
			(size 0.1524 0.1524)
			(layers "F.Cu" "F.Mask" "F.Paste")
			(net "FAN_TACH2")
			(options
				(clearance outline)
				(anchor circle)
			)
			(primitives
				(gr_poly
					(pts
						(arc
							(start 0.3048 -0.2032)
							(mid 0.275042 -0.275042)
							(end 0.2032 -0.3048)
						)
						(arc
							(start -0.2032 -0.3048)
							(mid -0.275042 -0.275042)
							(end -0.3048 -0.2032)
						)
						(arc
							(start -0.3048 0.2032)
							(mid -0.275042 0.275042)
							(end -0.2032 0.3048)
						)
						(arc
							(start 0.2032 0.3048)
							(mid 0.275042 0.275042)
							(end 0.3048 0.2032)
						)
					)
					(width 0)
					(fill yes)
				)
			)
		)
		(pad "2" smd custom
			(at 0 0.4445 90)
			(size 0.1524 0.1524)
			(layers "F.Cu" "F.Mask" "F.Paste")
			(net "GND")
			(options
				(clearance outline)
				(anchor circle)
			)
			(primitives
				(gr_poly
					(pts
						(arc
							(start 0.3048 -0.2032)
							(mid 0.275042 -0.275042)
							(end 0.2032 -0.3048)
						)
						(arc
							(start -0.2032 -0.3048)
							(mid -0.275042 -0.275042)
							(end -0.3048 -0.2032)
						)
						(arc
							(start -0.3048 0.2032)
							(mid -0.275042 0.275042)
							(end -0.2032 0.3048)
						)
						(arc
							(start 0.2032 0.3048)
							(mid 0.275042 0.275042)
							(end 0.3048 0.2032)
						)
					)
					(width 0)
					(fill yes)
				)
			)
		)
	)
	(footprint ""
		(layer "F.Cu")
		(at 23.622 -366.4712 -90)
		(property "Reference" "C58"
			(at 0 0 270)
			(layer "F.SilkS")
			(hide yes)
			(effects
				(font
					(size 1.27 1.27)
				)
			)
		)
		(property "Value" "SCD1U25V2KX-GP"
			(at 1.1811 -2.7051 270)
			(unlocked yes)
			(layer "F.Fab")
			(hide yes)
			(effects
				(font
					(size 1.016 1.016)
					(thickness 0.1524)
				)
			)
		)
		(property "Device Type" "C402H22"
			(at 1.1811 -4.2291 270)
			(unlocked yes)
			(layer "F.Fab")
			(hide yes)
			(effects
				(font
					(size 1.016 1.016)
					(thickness 0.1524)
				)
			)
		)
		(duplicate_pad_numbers_are_jumpers no)
		(fp_rect
			(start -0.4318 0.9525)
			(end 0.4318 -0.9525)
			(stroke
				(width 0)
				(type default)
			)
			(fill no)
			(layer "F.CrtYd")
		)
		(fp_rect
			(start -0.4318 0.9525)
			(end 0.4318 -0.9525)
			(stroke
				(width 0)
				(type default)
			)
			(fill no)
			(layer "F.Fab")
		)
		(pad "1" smd custom
			(at 0 -0.4445 270)
			(size 0.1524 0.1524)
			(layers "F.Cu" "F.Mask" "F.Paste")
			(net "ADM1276_ISET")
			(options
				(clearance outline)
				(anchor circle)
			)
			(primitives
				(gr_poly
					(pts
						(arc
							(start 0.3048 -0.2032)
							(mid 0.275042 -0.275042)
							(end 0.2032 -0.3048)
						)
						(arc
							(start -0.2032 -0.3048)
							(mid -0.275042 -0.275042)
							(end -0.3048 -0.2032)
						)
						(arc
							(start -0.3048 0.2032)
							(mid -0.275042 0.275042)
							(end -0.2032 0.3048)
						)
						(arc
							(start 0.2032 0.3048)
							(mid 0.275042 0.275042)
							(end 0.3048 0.2032)
						)
					)
					(width 0)
					(fill yes)
				)
			)
		)
		(pad "2" smd custom
			(at 0 0.4445 270)
			(size 0.1524 0.1524)
			(layers "F.Cu" "F.Mask" "F.Paste")
			(net "GND")
			(options
				(clearance outline)
				(anchor circle)
			)
			(primitives
				(gr_poly
					(pts
						(arc
							(start 0.3048 -0.2032)
							(mid 0.275042 -0.275042)
							(end 0.2032 -0.3048)
						)
						(arc
							(start -0.2032 -0.3048)
							(mid -0.275042 -0.275042)
							(end -0.3048 -0.2032)
						)
						(arc
							(start -0.3048 0.2032)
							(mid -0.275042 0.275042)
							(end -0.2032 0.3048)
						)
						(arc
							(start 0.2032 0.3048)
							(mid 0.275042 0.275042)
							(end 0.3048 0.2032)
						)
					)
					(width 0)
					(fill yes)
				)
			)
		)
	)
	(footprint ""
		(layer "F.Cu")
		(at 27.686 -381 180)
		(property "Reference" "PR17"
			(at 0 0 180)
			(layer "F.SilkS")
			(hide yes)
			(effects
				(font
					(size 1.27 1.27)
				)
			)
		)
		(property "Value" "10R2F-L-GP"
			(at 0.064008 -3.993896 180)
			(unlocked yes)
			(layer "F.Fab")
			(hide yes)
			(effects
				(font
					(size 1.016 1.016)
					(thickness 0.1524)
				)
			)
		)
		(property "Device Type" "R402H14"
			(at 0.064008 -5.517896 180)
			(unlocked yes)
			(layer "F.Fab")
			(hide yes)
			(effects
				(font
					(size 1.016 1.016)
					(thickness 0.1524)
				)
			)
		)
		(duplicate_pad_numbers_are_jumpers no)
		(fp_line
			(start 0.508 -0.9398)
			(end -0.508 -0.9398)
			(stroke
				(width 0.1524)
				(type default)
			)
			(layer "F.SilkS")
		)
		(fp_line
			(start -0.508 -0.9398)
			(end -0.508 0.9398)
			(stroke
				(width 0.1524)
				(type default)
			)
			(layer "F.SilkS")
		)
		(fp_rect
			(start -0.508 0.9398)
			(end 0.508 -0.9398)
			(stroke
				(width 0)
				(type default)
			)
			(fill no)
			(layer "F.CrtYd")
		)
		(fp_rect
			(start -0.508 0.9398)
			(end 0.508 -0.9398)
			(stroke
				(width 0)
				(type default)
			)
			(fill no)
			(layer "F.Fab")
		)
		(pad "1" smd custom
			(at 0 -0.4445 180)
			(size 0.1397 0.1397)
			(layers "F.Cu" "F.Mask" "F.Paste")
			(net "ADM1276_SENSE+")
			(options
				(clearance outline)
				(anchor circle)
			)
			(primitives
				(gr_poly
					(pts
						(arc
							(start -0.1778 -0.2794)
							(mid -0.249642 -0.249642)
							(end -0.2794 -0.1778)
						)
						(arc
							(start -0.2794 0.1778)
							(mid -0.249642 0.249642)
							(end -0.1778 0.2794)
						)
						(arc
							(start 0.1778 0.2794)
							(mid 0.249642 0.249642)
							(end 0.2794 0.1778)
						)
						(arc
							(start 0.2794 -0.1778)
							(mid 0.249642 -0.249642)
							(end 0.1778 -0.2794)
						)
					)
					(width 0)
					(fill yes)
				)
			)
		)
		(pad "2" smd custom
			(at 0 0.4445 180)
			(size 0.1397 0.1397)
			(layers "F.Cu" "F.Mask" "F.Paste")
			(net "SENSE+_R4")
			(options
				(clearance outline)
				(anchor circle)
			)
			(primitives
				(gr_poly
					(pts
						(arc
							(start -0.1778 -0.2794)
							(mid -0.249642 -0.249642)
							(end -0.2794 -0.1778)
						)
						(arc
							(start -0.2794 0.1778)
							(mid -0.249642 0.249642)
							(end -0.1778 0.2794)
						)
						(arc
							(start 0.1778 0.2794)
							(mid 0.249642 0.249642)
							(end 0.2794 0.1778)
						)
						(arc
							(start 0.2794 -0.1778)
							(mid 0.249642 -0.249642)
							(end 0.1778 -0.2794)
						)
					)
					(width 0)
					(fill yes)
				)
			)
		)
	)
	(footprint ""
		(layer "F.Cu")
		(at 18.8214 -259.3086 -90)
		(property "Reference" "R78"
			(at 0 0 270)
			(layer "F.SilkS")
			(hide yes)
			(effects
				(font
					(size 1.27 1.27)
				)
			)
		)
		(property "Value" "4K7R2F-GP"
			(at 0.064008 -3.993896 270)
			(unlocked yes)
			(layer "F.Fab")
			(hide yes)
			(effects
				(font
					(size 1.016 1.016)
					(thickness 0.1524)
				)
			)
		)
		(property "Device Type" "R402H16"
			(at 0.064008 -5.517896 270)
			(unlocked yes)
			(layer "F.Fab")
			(hide yes)
			(effects
				(font
					(size 1.016 1.016)
					(thickness 0.1524)
				)
			)
		)
		(duplicate_pad_numbers_are_jumpers no)
		(fp_line
			(start -0.508 -0.9398)
			(end -0.508 0.9398)
			(stroke
				(width 0.1524)
				(type default)
			)
			(layer "F.SilkS")
		)
		(fp_line
			(start 0.508 -0.9398)
			(end -0.508 -0.9398)
			(stroke
				(width 0.1524)
				(type default)
			)
			(layer "F.SilkS")
		)
		(fp_rect
			(start -0.508 0.9398)
			(end 0.508 -0.9398)
			(stroke
				(width 0)
				(type default)
			)
			(fill no)
			(layer "F.CrtYd")
		)
		(fp_rect
			(start -0.508 0.9398)
			(end 0.508 -0.9398)
			(stroke
				(width 0)
				(type default)
			)
			(fill no)
			(layer "F.Fab")
		)
		(pad "1" smd custom
			(at 0 -0.4445 270)
			(size 0.1397 0.1397)
			(layers "F.Cu" "F.Mask" "F.Paste")
			(net "P12V")
			(options
				(clearance outline)
				(anchor circle)
			)
			(primitives
				(gr_poly
					(pts
						(arc
							(start -0.1778 -0.2794)
							(mid -0.249642 -0.249642)
							(end -0.2794 -0.1778)
						)
						(arc
							(start -0.2794 0.1778)
							(mid -0.249642 0.249642)
							(end -0.1778 0.2794)
						)
						(arc
							(start 0.1778 0.2794)
							(mid 0.249642 0.249642)
							(end 0.2794 0.1778)
						)
						(arc
							(start 0.2794 -0.1778)
							(mid 0.249642 -0.249642)
							(end 0.1778 -0.2794)
						)
					)
					(width 0)
					(fill yes)
				)
			)
		)
		(pad "2" smd custom
			(at 0 0.4445 270)
			(size 0.1397 0.1397)
			(layers "F.Cu" "F.Mask" "F.Paste")
			(net "PWM_OUT_FAN3_NET")
			(options
				(clearance outline)
				(anchor circle)
			)
			(primitives
				(gr_poly
					(pts
						(arc
							(start -0.1778 -0.2794)
							(mid -0.249642 -0.249642)
							(end -0.2794 -0.1778)
						)
						(arc
							(start -0.2794 0.1778)
							(mid -0.249642 0.249642)
							(end -0.1778 0.2794)
						)
						(arc
							(start 0.1778 0.2794)
							(mid 0.249642 0.249642)
							(end 0.2794 0.1778)
						)
						(arc
							(start 0.2794 -0.1778)
							(mid 0.249642 -0.249642)
							(end 0.1778 -0.2794)
						)
					)
					(width 0)
					(fill yes)
				)
			)
		)
	)
	(footprint ""
		(layer "F.Cu")
		(at 18.0594 -262.1534 90)
		(property "Reference" "D5"
			(at 0 0 90)
			(layer "F.SilkS")
			(hide yes)
			(effects
				(font
					(size 1.27 1.27)
				)
			)
		)
		(property "Value" "BAS16H-GP"
			(at 0 -5.5372 90)
			(unlocked yes)
			(layer "F.Fab")
			(hide yes)
			(effects
				(font
					(size 1.016 1.016)
					(thickness 0.1524)
				)
			)
		)
		(property "Device Type" "SOD123AKH48"
			(at 0 -7.0612 90)
			(unlocked yes)
			(layer "F.Fab")
			(hide yes)
			(effects
				(font
					(size 1.016 1.016)
					(thickness 0.1524)
				)
			)
		)
		(duplicate_pad_numbers_are_jumpers no)
		(fp_line
			(start 1.016 -2.667)
			(end -1.016 -2.667)
			(stroke
				(width 0.1524)
				(type default)
			)
			(layer "F.SilkS")
		)
		(fp_line
			(start -1.016 -2.667)
			(end -1.016 2.667)
			(stroke
				(width 0.1524)
				(type default)
			)
			(layer "F.SilkS")
		)
		(fp_line
			(start 1.016 2.667)
			(end 1.016 -2.667)
			(stroke
				(width 0.1524)
				(type default)
			)
			(layer "F.SilkS")
		)
		(fp_line
			(start -1.016 2.667)
			(end 1.016 2.667)
			(stroke
				(width 0.1524)
				(type default)
			)
			(layer "F.SilkS")
		)
		(fp_line
			(start 0.889 2.921)
			(end -0.889 2.921)
			(stroke
				(width 0.508)
				(type default)
			)
			(layer "F.SilkS")
		)
		(fp_rect
			(start -1.143 3.175)
			(end 1.143 -2.794)
			(stroke
				(width 0)
				(type default)
			)
			(fill no)
			(layer "F.CrtYd")
		)
		(fp_poly
			(pts
				(xy -1.143 -2.794) (xy 1.143 -2.794) (xy 1.143 3.175) (xy -1.143 3.175)
			)
			(stroke
				(width 0)
				(type default)
			)
			(fill no)
			(layer "F.Fab")
		)
		(pad "A" smd rect
			(at 0 -1.6891 90)
			(size 0.889 1.397)
			(layers "F.Cu" "F.Mask" "F.Paste")
			(net "FAN_TACH6")
		)
		(pad "K" smd rect
			(at 0 1.6891 90)
			(size 0.889 1.397)
			(layers "F.Cu" "F.Mask" "F.Paste")
			(net "P12V")
		)
	)
	(footprint ""
		(layer "F.Cu")
		(at 26.035 -268.8336 90)
		(property "Reference" "C40"
			(at 0 0 90)
			(layer "F.SilkS")
			(hide yes)
			(effects
				(font
					(size 1.27 1.27)
				)
			)
		)
		(property "Value" "SC1U25V3KX-1-GP"
			(at 0 -2.8194 90)
			(unlocked yes)
			(layer "F.Fab")
			(hide yes)
			(effects
				(font
					(size 1.016 1.016)
					(thickness 0.1524)
				)
			)
		)
		(property "Device Type" "C603H36"
			(at 0 -4.3434 90)
			(unlocked yes)
			(layer "F.Fab")
			(hide yes)
			(effects
				(font
					(size 1.016 1.016)
					(thickness 0.1524)
				)
			)
		)
		(duplicate_pad_numbers_are_jumpers no)
		(fp_line
			(start 0.508 0)
			(end -0.508 0)
			(stroke
				(width 0.2032)
				(type default)
			)
			(layer "F.SilkS")
		)
		(fp_rect
			(start -0.5842 1.3335)
			(end 0.5842 -1.3335)
			(stroke
				(width 0)
				(type default)
			)
			(fill no)
			(layer "F.CrtYd")
		)
		(fp_rect
			(start -0.5842 1.3335)
			(end 0.5842 -1.3335)
			(stroke
				(width 0)
				(type default)
			)
			(fill no)
			(layer "F.Fab")
		)
		(pad "1" smd custom
			(at 0 -0.762 90)
			(size 0.2159 0.2159)
			(layers "F.Cu" "F.Mask" "F.Paste")
			(net "P12V")
			(options
				(clearance outline)
				(anchor circle)
			)
			(primitives
				(gr_poly
					(pts
						(arc
							(start -0.3302 -0.4318)
							(mid -0.402042 -0.402042)
							(end -0.4318 -0.3302)
						)
						(arc
							(start -0.4318 0.3302)
							(mid -0.402042 0.402042)
							(end -0.3302 0.4318)
						)
						(arc
							(start 0.3302 0.4318)
							(mid 0.402042 0.402042)
							(end 0.4318 0.3302)
						)
						(arc
							(start 0.4318 -0.3302)
							(mid 0.402042 -0.402042)
							(end 0.3302 -0.4318)
						)
					)
					(width 0)
					(fill yes)
				)
			)
		)
		(pad "2" smd custom
			(at 0 0.762 90)
			(size 0.2159 0.2159)
			(layers "F.Cu" "F.Mask" "F.Paste")
			(net "GND")
			(options
				(clearance outline)
				(anchor circle)
			)
			(primitives
				(gr_poly
					(pts
						(arc
							(start -0.3302 -0.4318)
							(mid -0.402042 -0.402042)
							(end -0.4318 -0.3302)
						)
						(arc
							(start -0.4318 0.3302)
							(mid -0.402042 0.402042)
							(end -0.3302 0.4318)
						)
						(arc
							(start 0.3302 0.4318)
							(mid 0.402042 0.402042)
							(end 0.4318 0.3302)
						)
						(arc
							(start 0.4318 -0.3302)
							(mid 0.402042 -0.402042)
							(end 0.3302 -0.4318)
						)
					)
					(width 0)
					(fill yes)
				)
			)
		)
	)
	(footprint ""
		(layer "F.Cu")
		(at 13.7922 -66.4464 180)
		(property "Reference" "R151"
			(at 0 0 180)
			(layer "F.SilkS")
			(hide yes)
			(effects
				(font
					(size 1.27 1.27)
				)
			)
		)
		(property "Value" "10R2F-L-GP"
			(at 0.064008 -3.993896 180)
			(unlocked yes)
			(layer "F.Fab")
			(hide yes)
			(effects
				(font
					(size 1.016 1.016)
					(thickness 0.1524)
				)
			)
		)
		(property "Device Type" "R402H14"
			(at 0.064008 -5.517896 180)
			(unlocked yes)
			(layer "F.Fab")
			(hide yes)
			(effects
				(font
					(size 1.016 1.016)
					(thickness 0.1524)
				)
			)
		)
		(duplicate_pad_numbers_are_jumpers no)
		(fp_line
			(start 0.508 -0.9398)
			(end -0.508 -0.9398)
			(stroke
				(width 0.1524)
				(type default)
			)
			(layer "F.SilkS")
		)
		(fp_line
			(start -0.508 -0.9398)
			(end -0.508 0.9398)
			(stroke
				(width 0.1524)
				(type default)
			)
			(layer "F.SilkS")
		)
		(fp_rect
			(start -0.508 0.9398)
			(end 0.508 -0.9398)
			(stroke
				(width 0)
				(type default)
			)
			(fill no)
			(layer "F.CrtYd")
		)
		(fp_rect
			(start -0.508 0.9398)
			(end 0.508 -0.9398)
			(stroke
				(width 0)
				(type default)
			)
			(fill no)
			(layer "F.Fab")
		)
		(pad "1" smd custom
			(at 0 -0.4445 180)
			(size 0.1397 0.1397)
			(layers "F.Cu" "F.Mask" "F.Paste")
			(net "I2C_C_SCL_CONN_R")
			(options
				(clearance outline)
				(anchor circle)
			)
			(primitives
				(gr_poly
					(pts
						(arc
							(start -0.1778 -0.2794)
							(mid -0.249642 -0.249642)
							(end -0.2794 -0.1778)
						)
						(arc
							(start -0.2794 0.1778)
							(mid -0.249642 0.249642)
							(end -0.1778 0.2794)
						)
						(arc
							(start 0.1778 0.2794)
							(mid 0.249642 0.249642)
							(end 0.2794 0.1778)
						)
						(arc
							(start 0.2794 -0.1778)
							(mid 0.249642 -0.249642)
							(end 0.1778 -0.2794)
						)
					)
					(width 0)
					(fill yes)
				)
			)
		)
		(pad "2" smd custom
			(at 0 0.4445 180)
			(size 0.1397 0.1397)
			(layers "F.Cu" "F.Mask" "F.Paste")
			(net "I2C_C_SCL")
			(options
				(clearance outline)
				(anchor circle)
			)
			(primitives
				(gr_poly
					(pts
						(arc
							(start -0.1778 -0.2794)
							(mid -0.249642 -0.249642)
							(end -0.2794 -0.1778)
						)
						(arc
							(start -0.2794 0.1778)
							(mid -0.249642 0.249642)
							(end -0.1778 0.2794)
						)
						(arc
							(start 0.1778 0.2794)
							(mid 0.249642 0.249642)
							(end 0.2794 0.1778)
						)
						(arc
							(start 0.2794 -0.1778)
							(mid 0.249642 -0.249642)
							(end 0.1778 -0.2794)
						)
					)
					(width 0)
					(fill yes)
				)
			)
		)
	)
	(footprint ""
		(layer "F.Cu")
		(at 17.018 -185.42 -90)
		(property "Reference" "R79"
			(at 0 0 270)
			(layer "F.SilkS")
			(hide yes)
			(effects
				(font
					(size 1.27 1.27)
				)
			)
		)
		(property "Value" "4K7R2F-GP"
			(at 0.064008 -3.993896 270)
			(unlocked yes)
			(layer "F.Fab")
			(hide yes)
			(effects
				(font
					(size 1.016 1.016)
					(thickness 0.1524)
				)
			)
		)
		(property "Device Type" "R402H16"
			(at 0.064008 -5.517896 270)
			(unlocked yes)
			(layer "F.Fab")
			(hide yes)
			(effects
				(font
					(size 1.016 1.016)
					(thickness 0.1524)
				)
			)
		)
		(duplicate_pad_numbers_are_jumpers no)
		(fp_line
			(start -0.508 -0.9398)
			(end -0.508 0.9398)
			(stroke
				(width 0.1524)
				(type default)
			)
			(layer "F.SilkS")
		)
		(fp_line
			(start 0.508 -0.9398)
			(end -0.508 -0.9398)
			(stroke
				(width 0.1524)
				(type default)
			)
			(layer "F.SilkS")
		)
		(fp_rect
			(start -0.508 0.9398)
			(end 0.508 -0.9398)
			(stroke
				(width 0)
				(type default)
			)
			(fill no)
			(layer "F.CrtYd")
		)
		(fp_rect
			(start -0.508 0.9398)
			(end 0.508 -0.9398)
			(stroke
				(width 0)
				(type default)
			)
			(fill no)
			(layer "F.Fab")
		)
		(pad "1" smd custom
			(at 0 -0.4445 270)
			(size 0.1397 0.1397)
			(layers "F.Cu" "F.Mask" "F.Paste")
			(net "P12V")
			(options
				(clearance outline)
				(anchor circle)
			)
			(primitives
				(gr_poly
					(pts
						(arc
							(start -0.1778 -0.2794)
							(mid -0.249642 -0.249642)
							(end -0.2794 -0.1778)
						)
						(arc
							(start -0.2794 0.1778)
							(mid -0.249642 0.249642)
							(end -0.1778 0.2794)
						)
						(arc
							(start 0.1778 0.2794)
							(mid 0.249642 0.249642)
							(end 0.2794 0.1778)
						)
						(arc
							(start 0.2794 -0.1778)
							(mid 0.249642 -0.249642)
							(end 0.1778 -0.2794)
						)
					)
					(width 0)
					(fill yes)
				)
			)
		)
		(pad "2" smd custom
			(at 0 0.4445 270)
			(size 0.1397 0.1397)
			(layers "F.Cu" "F.Mask" "F.Paste")
			(net "PWM_OUT_FAN4_NET")
			(options
				(clearance outline)
				(anchor circle)
			)
			(primitives
				(gr_poly
					(pts
						(arc
							(start -0.1778 -0.2794)
							(mid -0.249642 -0.249642)
							(end -0.2794 -0.1778)
						)
						(arc
							(start -0.2794 0.1778)
							(mid -0.249642 0.249642)
							(end -0.1778 0.2794)
						)
						(arc
							(start 0.1778 0.2794)
							(mid 0.249642 0.249642)
							(end 0.2794 0.1778)
						)
						(arc
							(start 0.2794 -0.1778)
							(mid 0.249642 -0.249642)
							(end 0.1778 -0.2794)
						)
					)
					(width 0)
					(fill yes)
				)
			)
		)
	)
)
